# S9S_MB_2U (Grand Teton) — schematic netlist excerpt (pin names and nets, part order shuffled) for the footprints in the layout excerpt that follows; sources: Cadence DE-HDL packaged netlist, KiCad conversion of 03242023_DA0F0TMBIJ0_F0T_Motherboard_J_brd_V01_OCP.brd

R285  Q_RES  10K 1% CHIP  pkg 0402LF  page 119 : A = P3V3_AUX ; B = FM_CPU0_PKGID2
PC2260  Q_CAP  22UF 16V 20% X6S  pkg C0805  page 259 : A = SW_P3V3_AUX_FLT ; B = GND
PR3917  Q_RES  0 5% CHIP  pkg 0402LF  page 302 : A = HSC_SCREF ; B = HSC_SCREF_2

(kicad_pcb
	(version 20260206)
	(generator "pcbnew")
	(generator_version "10.0")
	(general
		(thickness 1.6)
		(legacy_teardrops no)
	)
	(paper "A4")
	(title_block
		(title "03242023_DA0F0TMBIJ0_F0T_Motherboard_J_brd_V01_OCP.brd")
		(comment 1 "Grand Teton / footprints 1434-1436 of 6105")
	)
	(layers
		(0 "F.Cu" signal "TOP")
		(4 "In1.Cu" signal "GND")
		(6 "In2.Cu" signal "IN1")
		(8 "In3.Cu" signal "GND1")
		(10 "In4.Cu" signal "IN2")
		(12 "In5.Cu" signal "GND2")
		(14 "In6.Cu" signal "IN3")
		(16 "In7.Cu" signal "GND3")
		(18 "In8.Cu" signal "VCC")
		(20 "In9.Cu" signal "VCC1")
		(22 "In10.Cu" signal "GND4")
		(24 "In11.Cu" signal "IN4")
		(26 "In12.Cu" signal "GND5")
		(28 "In13.Cu" signal "IN5")
		(30 "In14.Cu" signal "GND6")
		(32 "In15.Cu" signal "IN6")
		(34 "In16.Cu" signal "GND7")
		(2 "B.Cu" signal "BOTTOM")
		(9 "F.Adhes" user "F.Adhesive")
		(11 "B.Adhes" user "B.Adhesive")
		(13 "F.Paste" user "Package Geometry/Pastemask Top")
		(15 "B.Paste" user "Package Geometry/Pastemask Bottom")
		(5 "F.SilkS" user "Ref Des/Silkscreen Top")
		(7 "B.SilkS" user "Ref Des/Silkscreen Bottom")
		(1 "F.Mask" user "Board Geometry/Soldermask Top")
		(3 "B.Mask" user "Board Geometry/Soldermask Bottom")
		(17 "Dwgs.User" user "User.Drawings")
		(19 "Cmts.User" user "User.Comments")
		(21 "Eco1.User" user "User.Eco1")
		(23 "Eco2.User" user "User.Eco2")
		(25 "Edge.Cuts" user "Board Geometry/Outline")
		(27 "Margin" user)
		(31 "F.CrtYd" user "Package Geometry/Place Bound Top")
		(29 "B.CrtYd" user "Package Geometry/Place Bound Bottom")
		(35 "F.Fab" user "Ref Des/Assembly Top")
		(33 "B.Fab" user "Ref Des/Assembly Bottom")
	)
	(footprint ""
		(layer "F.Cu")
		(at 205.397608 -408.887422)
		(property "Reference" "PR3917"
			(at 0 0 0)
			(layer "F.SilkS")
			(hide yes)
			(effects
				(font
					(size 1.27 1.27)
				)
			)
		)
		(property "Value" ""
			(at 0 0 0)
			(layer "F.Fab")
			(effects
				(font
					(size 1.27 1.27)
				)
			)
		)
		(duplicate_pad_numbers_are_jumpers no)
		(fp_line
			(start -0.7874 -0.4064)
			(end 0.7874 -0.4064)
			(stroke
				(width 0.1524)
				(type default)
			)
			(layer "F.SilkS")
		)
		(fp_line
			(start -0.7874 0.4064)
			(end -0.7874 -0.4064)
			(stroke
				(width 0.1524)
				(type default)
			)
			(layer "F.SilkS")
		)
		(fp_line
			(start 0.7874 -0.4064)
			(end 0.7874 0.4064)
			(stroke
				(width 0.1524)
				(type default)
			)
			(layer "F.SilkS")
		)
		(fp_line
			(start 0.7874 0.4064)
			(end -0.7874 0.4064)
			(stroke
				(width 0.1524)
				(type default)
			)
			(layer "F.SilkS")
		)
		(fp_line
			(start -0.67945 -0.305054)
			(end -0.12065 -0.305054)
			(stroke
				(width 0.1)
				(type default)
			)
			(layer "F.Fab")
		)
		(fp_line
			(start -0.67945 0.3048)
			(end -0.67945 -0.305054)
			(stroke
				(width 0.1)
				(type default)
			)
			(layer "F.Fab")
		)
		(fp_line
			(start -0.12065 -0.305054)
			(end -0.12065 -0.2794)
			(stroke
				(width 0.1)
				(type default)
			)
			(layer "F.Fab")
		)
		(fp_line
			(start -0.12065 -0.2794)
			(end 0.12065 -0.2794)
			(stroke
				(width 0.1)
				(type default)
			)
			(layer "F.Fab")
		)
		(fp_line
			(start -0.12065 0.2794)
			(end -0.12065 0.3048)
			(stroke
				(width 0.1)
				(type default)
			)
			(layer "F.Fab")
		)
		(fp_line
			(start -0.12065 0.3048)
			(end -0.67945 0.3048)
			(stroke
				(width 0.1)
				(type default)
			)
			(layer "F.Fab")
		)
		(fp_line
			(start 0.120396 0.2794)
			(end -0.12065 0.2794)
			(stroke
				(width 0.1)
				(type default)
			)
			(layer "F.Fab")
		)
		(fp_line
			(start 0.120396 0.3048)
			(end 0.120396 0.2794)
			(stroke
				(width 0.1)
				(type default)
			)
			(layer "F.Fab")
		)
		(fp_line
			(start 0.12065 -0.3048)
			(end 0.67945 -0.3048)
			(stroke
				(width 0.1)
				(type default)
			)
			(layer "F.Fab")
		)
		(fp_line
			(start 0.12065 -0.2794)
			(end 0.12065 -0.3048)
			(stroke
				(width 0.1)
				(type default)
			)
			(layer "F.Fab")
		)
		(fp_line
			(start 0.67945 -0.3048)
			(end 0.67945 0.3048)
			(stroke
				(width 0.1)
				(type default)
			)
			(layer "F.Fab")
		)
		(fp_line
			(start 0.67945 0.3048)
			(end 0.120396 0.3048)
			(stroke
				(width 0.1)
				(type default)
			)
			(layer "F.Fab")
		)
		(pad "1" smd circle
			(at -0.40005 0)
			(size 0 0)
			(layers "F.Cu" "F.Mask" "F.Paste")
			(net "HSC_SCREF")
		)
		(pad "2" smd circle
			(at 0.40005 0)
			(size 0 0)
			(layers "F.Cu" "F.Mask" "F.Paste")
			(net "HSC_SCREF_2")
		)
	)
	(footprint ""
		(layer "F.Cu")
		(at 183.69788 -126.964948 -90)
		(property "Reference" "R285"
			(at 0 0 270)
			(layer "F.SilkS")
			(hide yes)
			(effects
				(font
					(size 1.27 1.27)
				)
			)
		)
		(property "Value" ""
			(at 0 0 270)
			(layer "F.Fab")
			(effects
				(font
					(size 1.27 1.27)
				)
			)
		)
		(duplicate_pad_numbers_are_jumpers no)
		(fp_line
			(start -0.7874 0.4064)
			(end -0.7874 -0.4064)
			(stroke
				(width 0.1524)
				(type default)
			)
			(layer "F.SilkS")
		)
		(fp_line
			(start 0.7874 0.4064)
			(end -0.7874 0.4064)
			(stroke
				(width 0.1524)
				(type default)
			)
			(layer "F.SilkS")
		)
		(fp_line
			(start -0.7874 -0.4064)
			(end 0.7874 -0.4064)
			(stroke
				(width 0.1524)
				(type default)
			)
			(layer "F.SilkS")
		)
		(fp_line
			(start 0.7874 -0.4064)
			(end 0.7874 0.4064)
			(stroke
				(width 0.1524)
				(type default)
			)
			(layer "F.SilkS")
		)
		(fp_line
			(start -0.67945 0.3048)
			(end -0.67945 -0.305054)
			(stroke
				(width 0.1)
				(type default)
			)
			(layer "F.Fab")
		)
		(fp_line
			(start -0.12065 0.3048)
			(end -0.67945 0.3048)
			(stroke
				(width 0.1)
				(type default)
			)
			(layer "F.Fab")
		)
		(fp_line
			(start 0.120396 0.3048)
			(end 0.120396 0.2794)
			(stroke
				(width 0.1)
				(type default)
			)
			(layer "F.Fab")
		)
		(fp_line
			(start 0.67945 0.3048)
			(end 0.120396 0.3048)
			(stroke
				(width 0.1)
				(type default)
			)
			(layer "F.Fab")
		)
		(fp_line
			(start -0.12065 0.2794)
			(end -0.12065 0.3048)
			(stroke
				(width 0.1)
				(type default)
			)
			(layer "F.Fab")
		)
		(fp_line
			(start 0.120396 0.2794)
			(end -0.12065 0.2794)
			(stroke
				(width 0.1)
				(type default)
			)
			(layer "F.Fab")
		)
		(fp_line
			(start -0.12065 -0.2794)
			(end 0.12065 -0.2794)
			(stroke
				(width 0.1)
				(type default)
			)
			(layer "F.Fab")
		)
		(fp_line
			(start 0.12065 -0.2794)
			(end 0.12065 -0.3048)
			(stroke
				(width 0.1)
				(type default)
			)
			(layer "F.Fab")
		)
		(fp_line
			(start 0.12065 -0.3048)
			(end 0.67945 -0.3048)
			(stroke
				(width 0.1)
				(type default)
			)
			(layer "F.Fab")
		)
		(fp_line
			(start 0.67945 -0.3048)
			(end 0.67945 0.3048)
			(stroke
				(width 0.1)
				(type default)
			)
			(layer "F.Fab")
		)
		(fp_line
			(start -0.67945 -0.305054)
			(end -0.12065 -0.305054)
			(stroke
				(width 0.1)
				(type default)
			)
			(layer "F.Fab")
		)
		(fp_line
			(start -0.12065 -0.305054)
			(end -0.12065 -0.2794)
			(stroke
				(width 0.1)
				(type default)
			)
			(layer "F.Fab")
		)
		(pad "1" smd circle
			(at -0.40005 0 270)
			(size 0 0)
			(layers "F.Cu" "F.Mask" "F.Paste")
			(net "P3V3_AUX")
		)
		(pad "2" smd circle
			(at 0.40005 0 270)
			(size 0 0)
			(layers "F.Cu" "F.Mask" "F.Paste")
			(net "FM_CPU0_PKGID2")
		)
	)
	(footprint ""
		(layer "F.Cu")
		(at 458.298804 -76.588112 90)
		(property "Reference" "PC2260"
			(at 0 0 90)
			(layer "F.SilkS")
			(hide yes)
			(effects
				(font
					(size 1.27 1.27)
				)
			)
		)
		(property "Value" ""
			(at 0 0 90)
			(layer "F.Fab")
			(effects
				(font
					(size 1.27 1.27)
				)
			)
		)
		(duplicate_pad_numbers_are_jumpers no)
		(fp_line
			(start 1.524 -0.762)
			(end 1.524 0.762)
			(stroke
				(width 0.1524)
				(type default)
			)
			(layer "F.SilkS")
		)
		(fp_line
			(start -1.524 -0.762)
			(end 1.524 -0.762)
			(stroke
				(width 0.1524)
				(type default)
			)
			(layer "F.SilkS")
		)
		(fp_line
			(start 1.524 0.762)
			(end -1.524 0.762)
			(stroke
				(width 0.1524)
				(type default)
			)
			(layer "F.SilkS")
		)
		(fp_line
			(start -1.524 0.762)
			(end -1.524 -0.762)
			(stroke
				(width 0.1524)
				(type default)
			)
			(layer "F.SilkS")
		)
		(fp_line
			(start 1.1049 -0.724916)
			(end -1.1049 -0.724916)
			(stroke
				(width 0.1)
				(type default)
			)
			(layer "F.Fab")
		)
		(fp_line
			(start -1.1049 -0.724916)
			(end -1.1049 0.724916)
			(stroke
				(width 0.1)
				(type default)
			)
			(layer "F.Fab")
		)
		(fp_line
			(start 1.1049 0.724916)
			(end 1.1049 -0.724916)
			(stroke
				(width 0.1)
				(type default)
			)
			(layer "F.Fab")
		)
		(fp_line
			(start -1.1049 0.724916)
			(end 1.1049 0.724916)
			(stroke
				(width 0.1)
				(type default)
			)
			(layer "F.Fab")
		)
		(pad "1" smd rect
			(at -0.889 0 270)
			(size 1.016 1.27)
			(layers "F.Cu" "F.Mask" "F.Paste")
			(net "SW_P3V3_AUX_FLT")
		)
		(pad "2" smd rect
			(at 0.889 0 270)
			(size 1.016 1.27)
			(layers "F.Cu" "F.Mask" "F.Paste")
			(net "GND")
		)
	)
)
